(kicad_pcb
	(version 20260206)
	(generator "pcbnew")
	(generator_version "10.0")
	(general
		(thickness 1.6)
		(legacy_teardrops no)
	)
	(paper "A4")
	(title_block
		(title "03242023_DA0F0TMBIJ0_F0T_Motherboard_J_brd_V01_OCP.brd")
		(comment 1 "Grand Teton / footprints 5303-5309 of 6105")
	)
	(layers
		(0 "F.Cu" signal "TOP")
		(4 "In1.Cu" signal "GND")
		(6 "In2.Cu" signal "IN1")
		(8 "In3.Cu" signal "GND1")
		(10 "In4.Cu" signal "IN2")
		(12 "In5.Cu" signal "GND2")
		(14 "In6.Cu" signal "IN3")
		(16 "In7.Cu" signal "GND3")
		(18 "In8.Cu" signal "VCC")
		(20 "In9.Cu" signal "VCC1")
		(22 "In10.Cu" signal "GND4")
		(24 "In11.Cu" signal "IN4")
		(26 "In12.Cu" signal "GND5")
		(28 "In13.Cu" signal "IN5")
		(30 "In14.Cu" signal "GND6")
		(32 "In15.Cu" signal "IN6")
		(34 "In16.Cu" signal "GND7")
		(2 "B.Cu" signal "BOTTOM")
		(9 "F.Adhes" user "F.Adhesive")
		(11 "B.Adhes" user "B.Adhesive")
		(13 "F.Paste" user "Package Geometry/Pastemask Top")
		(15 "B.Paste" user "Package Geometry/Pastemask Bottom")
		(5 "F.SilkS" user "Ref Des/Silkscreen Top")
		(7 "B.SilkS" user "Ref Des/Silkscreen Bottom")
		(1 "F.Mask" user "Board Geometry/Soldermask Top")
		(3 "B.Mask" user "Board Geometry/Soldermask Bottom")
		(17 "Dwgs.User" user "User.Drawings")
		(19 "Cmts.User" user "User.Comments")
		(21 "Eco1.User" user "User.Eco1")
		(23 "Eco2.User" user "User.Eco2")
		(25 "Edge.Cuts" user "Board Geometry/Outline")
		(27 "Margin" user)
		(31 "F.CrtYd" user "Package Geometry/Place Bound Top")
		(29 "B.CrtYd" user "Package Geometry/Place Bound Bottom")
		(35 "F.Fab" user "Ref Des/Assembly Top")
		(33 "B.Fab" user "Ref Des/Assembly Bottom")
	)
	(footprint ""
		(layer "B.Cu")
		(at 338.553044 -32.437578 90)
		(property "Reference" "R1457"
			(at 0 0 90)
			(layer "B.SilkS")
			(hide yes)
			(effects
				(font
					(size 1.27 1.27)
				)
				(justify mirror)
			)
		)
		(property "Value" ""
			(at 0 0 90)
			(layer "B.Fab")
			(effects
				(font
					(size 1.27 1.27)
				)
				(justify mirror)
			)
		)
		(duplicate_pad_numbers_are_jumpers no)
		(fp_line
			(start 0.7874 -0.4064)
			(end -0.7874 -0.4064)
			(stroke
				(width 0.1524)
				(type default)
			)
			(layer "B.SilkS")
		)
		(fp_line
			(start -0.7874 -0.4064)
			(end -0.7874 0.4064)
			(stroke
				(width 0.1524)
				(type default)
			)
			(layer "B.SilkS")
		)
		(fp_line
			(start 0.7874 0.4064)
			(end 0.7874 -0.4064)
			(stroke
				(width 0.1524)
				(type default)
			)
			(layer "B.SilkS")
		)
		(fp_line
			(start -0.7874 0.4064)
			(end 0.7874 0.4064)
			(stroke
				(width 0.1524)
				(type default)
			)
			(layer "B.SilkS")
		)
		(fp_line
			(start 0.67945 -0.305054)
			(end 0.12065 -0.305054)
			(stroke
				(width 0.1)
				(type default)
			)
			(layer "B.Fab")
		)
		(fp_line
			(start 0.12065 -0.305054)
			(end 0.12065 -0.2794)
			(stroke
				(width 0.1)
				(type default)
			)
			(layer "B.Fab")
		)
		(fp_line
			(start -0.12065 -0.3048)
			(end -0.67945 -0.3048)
			(stroke
				(width 0.1)
				(type default)
			)
			(layer "B.Fab")
		)
		(fp_line
			(start -0.67945 -0.3048)
			(end -0.67945 0.3048)
			(stroke
				(width 0.1)
				(type default)
			)
			(layer "B.Fab")
		)
		(fp_line
			(start 0.12065 -0.2794)
			(end -0.12065 -0.2794)
			(stroke
				(width 0.1)
				(type default)
			)
			(layer "B.Fab")
		)
		(fp_line
			(start -0.12065 -0.2794)
			(end -0.12065 -0.3048)
			(stroke
				(width 0.1)
				(type default)
			)
			(layer "B.Fab")
		)
		(fp_line
			(start 0.12065 0.2794)
			(end 0.12065 0.3048)
			(stroke
				(width 0.1)
				(type default)
			)
			(layer "B.Fab")
		)
		(fp_line
			(start -0.120396 0.2794)
			(end 0.12065 0.2794)
			(stroke
				(width 0.1)
				(type default)
			)
			(layer "B.Fab")
		)
		(fp_line
			(start 0.67945 0.3048)
			(end 0.67945 -0.305054)
			(stroke
				(width 0.1)
				(type default)
			)
			(layer "B.Fab")
		)
		(fp_line
			(start 0.12065 0.3048)
			(end 0.67945 0.3048)
			(stroke
				(width 0.1)
				(type default)
			)
			(layer "B.Fab")
		)
		(fp_line
			(start -0.120396 0.3048)
			(end -0.120396 0.2794)
			(stroke
				(width 0.1)
				(type default)
			)
			(layer "B.Fab")
		)
		(fp_line
			(start -0.67945 0.3048)
			(end -0.120396 0.3048)
			(stroke
				(width 0.1)
				(type default)
			)
			(layer "B.Fab")
		)
		(pad "1" smd circle
			(at 0.40005 0 270)
			(size 0 0)
			(layers "B.Cu" "B.Mask" "B.Paste")
			(net "FM_XTAL_INPUT_FREQUENCY_1_MGPIO")
		)
		(pad "2" smd circle
			(at -0.40005 0 270)
			(size 0 0)
			(layers "B.Cu" "B.Mask" "B.Paste")
			(net "GND")
		)
	)
	(footprint ""
		(layer "B.Cu")
		(at 238.30788 -422.976548 90)
		(property "Reference" "C2297"
			(at 0 0 90)
			(layer "B.SilkS")
			(hide yes)
			(effects
				(font
					(size 1.27 1.27)
				)
				(justify mirror)
			)
		)
		(property "Value" ""
			(at 0 0 90)
			(layer "B.Fab")
			(effects
				(font
					(size 1.27 1.27)
				)
				(justify mirror)
			)
		)
		(duplicate_pad_numbers_are_jumpers no)
		(fp_line
			(start 0.7874 -0.4064)
			(end -0.7874 -0.4064)
			(stroke
				(width 0.1524)
				(type default)
			)
			(layer "B.SilkS")
		)
		(fp_line
			(start -0.7874 -0.4064)
			(end -0.7874 0.4064)
			(stroke
				(width 0.1524)
				(type default)
			)
			(layer "B.SilkS")
		)
		(fp_line
			(start 0.7874 0.4064)
			(end 0.7874 -0.4064)
			(stroke
				(width 0.1524)
				(type default)
			)
			(layer "B.SilkS")
		)
		(fp_line
			(start -0.7874 0.4064)
			(end 0.7874 0.4064)
			(stroke
				(width 0.1524)
				(type default)
			)
			(layer "B.SilkS")
		)
		(fp_line
			(start 0.67945 -0.305054)
			(end 0.12065 -0.305054)
			(stroke
				(width 0.1)
				(type default)
			)
			(layer "B.Fab")
		)
		(fp_line
			(start 0.12065 -0.305054)
			(end 0.12065 -0.2794)
			(stroke
				(width 0.1)
				(type default)
			)
			(layer "B.Fab")
		)
		(fp_line
			(start -0.12065 -0.3048)
			(end -0.67945 -0.3048)
			(stroke
				(width 0.1)
				(type default)
			)
			(layer "B.Fab")
		)
		(fp_line
			(start -0.67945 -0.3048)
			(end -0.67945 0.3048)
			(stroke
				(width 0.1)
				(type default)
			)
			(layer "B.Fab")
		)
		(fp_line
			(start 0.12065 -0.2794)
			(end -0.12065 -0.2794)
			(stroke
				(width 0.1)
				(type default)
			)
			(layer "B.Fab")
		)
		(fp_line
			(start -0.12065 -0.2794)
			(end -0.12065 -0.3048)
			(stroke
				(width 0.1)
				(type default)
			)
			(layer "B.Fab")
		)
		(fp_line
			(start 0.12065 0.2794)
			(end 0.12065 0.3048)
			(stroke
				(width 0.1)
				(type default)
			)
			(layer "B.Fab")
		)
		(fp_line
			(start -0.120396 0.2794)
			(end 0.12065 0.2794)
			(stroke
				(width 0.1)
				(type default)
			)
			(layer "B.Fab")
		)
		(fp_line
			(start 0.67945 0.3048)
			(end 0.67945 -0.305054)
			(stroke
				(width 0.1)
				(type default)
			)
			(layer "B.Fab")
		)
		(fp_line
			(start 0.12065 0.3048)
			(end 0.67945 0.3048)
			(stroke
				(width 0.1)
				(type default)
			)
			(layer "B.Fab")
		)
		(fp_line
			(start -0.120396 0.3048)
			(end -0.120396 0.2794)
			(stroke
				(width 0.1)
				(type default)
			)
			(layer "B.Fab")
		)
		(fp_line
			(start -0.67945 0.3048)
			(end -0.120396 0.3048)
			(stroke
				(width 0.1)
				(type default)
			)
			(layer "B.Fab")
		)
		(pad "1" smd circle
			(at 0.40005 0 270)
			(size 0 0)
			(layers "B.Cu" "B.Mask" "B.Paste")
			(net "FM_GPU_HSC_EN_BUF_R1")
		)
		(pad "2" smd circle
			(at -0.40005 0 270)
			(size 0 0)
			(layers "B.Cu" "B.Mask" "B.Paste")
			(net "GND")
		)
	)
	(footprint ""
		(layer "B.Cu")
		(at 179.091082 -422.273222 90)
		(property "Reference" "R2811"
			(at 0 0 90)
			(layer "B.SilkS")
			(hide yes)
			(effects
				(font
					(size 1.27 1.27)
				)
				(justify mirror)
			)
		)
		(property "Value" ""
			(at 0 0 90)
			(layer "B.Fab")
			(effects
				(font
					(size 1.27 1.27)
				)
				(justify mirror)
			)
		)
		(duplicate_pad_numbers_are_jumpers no)
		(fp_line
			(start 0.7874 -0.4064)
			(end -0.7874 -0.4064)
			(stroke
				(width 0.1524)
				(type default)
			)
			(layer "B.SilkS")
		)
		(fp_line
			(start -0.7874 -0.4064)
			(end -0.7874 0.4064)
			(stroke
				(width 0.1524)
				(type default)
			)
			(layer "B.SilkS")
		)
		(fp_line
			(start 0.7874 0.4064)
			(end 0.7874 -0.4064)
			(stroke
				(width 0.1524)
				(type default)
			)
			(layer "B.SilkS")
		)
		(fp_line
			(start -0.7874 0.4064)
			(end 0.7874 0.4064)
			(stroke
				(width 0.1524)
				(type default)
			)
			(layer "B.SilkS")
		)
		(fp_line
			(start 0.67945 -0.305054)
			(end 0.12065 -0.305054)
			(stroke
				(width 0.1)
				(type default)
			)
			(layer "B.Fab")
		)
		(fp_line
			(start 0.12065 -0.305054)
			(end 0.12065 -0.2794)
			(stroke
				(width 0.1)
				(type default)
			)
			(layer "B.Fab")
		)
		(fp_line
			(start -0.12065 -0.3048)
			(end -0.67945 -0.3048)
			(stroke
				(width 0.1)
				(type default)
			)
			(layer "B.Fab")
		)
		(fp_line
			(start -0.67945 -0.3048)
			(end -0.67945 0.3048)
			(stroke
				(width 0.1)
				(type default)
			)
			(layer "B.Fab")
		)
		(fp_line
			(start 0.12065 -0.2794)
			(end -0.12065 -0.2794)
			(stroke
				(width 0.1)
				(type default)
			)
			(layer "B.Fab")
		)
		(fp_line
			(start -0.12065 -0.2794)
			(end -0.12065 -0.3048)
			(stroke
				(width 0.1)
				(type default)
			)
			(layer "B.Fab")
		)
		(fp_line
			(start 0.12065 0.2794)
			(end 0.12065 0.3048)
			(stroke
				(width 0.1)
				(type default)
			)
			(layer "B.Fab")
		)
		(fp_line
			(start -0.120396 0.2794)
			(end 0.12065 0.2794)
			(stroke
				(width 0.1)
				(type default)
			)
			(layer "B.Fab")
		)
		(fp_line
			(start 0.67945 0.3048)
			(end 0.67945 -0.305054)
			(stroke
				(width 0.1)
				(type default)
			)
			(layer "B.Fab")
		)
		(fp_line
			(start 0.12065 0.3048)
			(end 0.67945 0.3048)
			(stroke
				(width 0.1)
				(type default)
			)
			(layer "B.Fab")
		)
		(fp_line
			(start -0.120396 0.3048)
			(end -0.120396 0.2794)
			(stroke
				(width 0.1)
				(type default)
			)
			(layer "B.Fab")
		)
		(fp_line
			(start -0.67945 0.3048)
			(end -0.120396 0.3048)
			(stroke
				(width 0.1)
				(type default)
			)
			(layer "B.Fab")
		)
		(pad "1" smd circle
			(at 0.40005 0 270)
			(size 0 0)
			(layers "B.Cu" "B.Mask" "B.Paste")
			(net "SMB_FAN_3V3AUX_BUF_SCL")
		)
		(pad "2" smd circle
			(at -0.40005 0 270)
			(size 0 0)
			(layers "B.Cu" "B.Mask" "B.Paste")
			(net "SMB_FAN_3V3AUX_BUF_R_SCL")
		)
	)
	(footprint ""
		(layer "B.Cu")
		(at 38.328346 -321.554856 -90)
		(property "Reference" "C58"
			(at 0 0 90)
			(layer "B.SilkS")
			(hide yes)
			(effects
				(font
					(size 1.27 1.27)
				)
				(justify mirror)
			)
		)
		(property "Value" ""
			(at 0 0 90)
			(layer "B.Fab")
			(effects
				(font
					(size 1.27 1.27)
				)
				(justify mirror)
			)
		)
		(duplicate_pad_numbers_are_jumpers no)
		(fp_line
			(start -1.524 0.762)
			(end 1.524 0.762)
			(stroke
				(width 0.1524)
				(type default)
			)
			(layer "B.SilkS")
		)
		(fp_line
			(start 1.524 0.762)
			(end 1.524 -0.762)
			(stroke
				(width 0.1524)
				(type default)
			)
			(layer "B.SilkS")
		)
		(fp_line
			(start -1.524 -0.762)
			(end -1.524 0.762)
			(stroke
				(width 0.1524)
				(type default)
			)
			(layer "B.SilkS")
		)
		(fp_line
			(start 1.524 -0.762)
			(end -1.524 -0.762)
			(stroke
				(width 0.1524)
				(type default)
			)
			(layer "B.SilkS")
		)
		(fp_line
			(start -1.1049 0.724916)
			(end -1.1049 -0.724916)
			(stroke
				(width 0.1)
				(type default)
			)
			(layer "B.Fab")
		)
		(fp_line
			(start 1.1049 0.724916)
			(end -1.1049 0.724916)
			(stroke
				(width 0.1)
				(type default)
			)
			(layer "B.Fab")
		)
		(fp_line
			(start -1.1049 -0.724916)
			(end 1.1049 -0.724916)
			(stroke
				(width 0.1)
				(type default)
			)
			(layer "B.Fab")
		)
		(fp_line
			(start 1.1049 -0.724916)
			(end 1.1049 0.724916)
			(stroke
				(width 0.1)
				(type default)
			)
			(layer "B.Fab")
		)
		(pad "1" smd rect
			(at 0.889 0 270)
			(size 1.016 1.27)
			(layers "B.Cu" "B.Mask" "B.Paste")
			(net "P12V_S3_AUX_CPU1_NVDIMM")
		)
		(pad "2" smd rect
			(at -0.889 0 270)
			(size 1.016 1.27)
			(layers "B.Cu" "B.Mask" "B.Paste")
			(net "GND")
		)
	)
	(footprint ""
		(layer "B.Cu")
		(at 432.562 -24.094948 -90)
		(property "Reference" "R1896"
			(at 0 0 90)
			(layer "B.SilkS")
			(hide yes)
			(effects
				(font
					(size 1.27 1.27)
				)
				(justify mirror)
			)
		)
		(property "Value" ""
			(at 0 0 90)
			(layer "B.Fab")
			(effects
				(font
					(size 1.27 1.27)
				)
				(justify mirror)
			)
		)
		(duplicate_pad_numbers_are_jumpers no)
		(fp_line
			(start -0.7874 0.4064)
			(end 0.7874 0.4064)
			(stroke
				(width 0.1524)
				(type default)
			)
			(layer "B.SilkS")
		)
		(fp_line
			(start 0.7874 0.4064)
			(end 0.7874 -0.4064)
			(stroke
				(width 0.1524)
				(type default)
			)
			(layer "B.SilkS")
		)
		(fp_line
			(start -0.7874 -0.4064)
			(end -0.7874 0.4064)
			(stroke
				(width 0.1524)
				(type default)
			)
			(layer "B.SilkS")
		)
		(fp_line
			(start 0.7874 -0.4064)
			(end -0.7874 -0.4064)
			(stroke
				(width 0.1524)
				(type default)
			)
			(layer "B.SilkS")
		)
		(fp_line
			(start -0.67945 0.3048)
			(end -0.120396 0.3048)
			(stroke
				(width 0.1)
				(type default)
			)
			(layer "B.Fab")
		)
		(fp_line
			(start -0.120396 0.3048)
			(end -0.120396 0.2794)
			(stroke
				(width 0.1)
				(type default)
			)
			(layer "B.Fab")
		)
		(fp_line
			(start 0.12065 0.3048)
			(end 0.67945 0.3048)
			(stroke
				(width 0.1)
				(type default)
			)
			(layer "B.Fab")
		)
		(fp_line
			(start 0.67945 0.3048)
			(end 0.67945 -0.305054)
			(stroke
				(width 0.1)
				(type default)
			)
			(layer "B.Fab")
		)
		(fp_line
			(start -0.120396 0.2794)
			(end 0.12065 0.2794)
			(stroke
				(width 0.1)
				(type default)
			)
			(layer "B.Fab")
		)
		(fp_line
			(start 0.12065 0.2794)
			(end 0.12065 0.3048)
			(stroke
				(width 0.1)
				(type default)
			)
			(layer "B.Fab")
		)
		(fp_line
			(start -0.12065 -0.2794)
			(end -0.12065 -0.3048)
			(stroke
				(width 0.1)
				(type default)
			)
			(layer "B.Fab")
		)
		(fp_line
			(start 0.12065 -0.2794)
			(end -0.12065 -0.2794)
			(stroke
				(width 0.1)
				(type default)
			)
			(layer "B.Fab")
		)
		(fp_line
			(start -0.67945 -0.3048)
			(end -0.67945 0.3048)
			(stroke
				(width 0.1)
				(type default)
			)
			(layer "B.Fab")
		)
		(fp_line
			(start -0.12065 -0.3048)
			(end -0.67945 -0.3048)
			(stroke
				(width 0.1)
				(type default)
			)
			(layer "B.Fab")
		)
		(fp_line
			(start 0.12065 -0.305054)
			(end 0.12065 -0.2794)
			(stroke
				(width 0.1)
				(type default)
			)
			(layer "B.Fab")
		)
		(fp_line
			(start 0.67945 -0.305054)
			(end 0.12065 -0.305054)
			(stroke
				(width 0.1)
				(type default)
			)
			(layer "B.Fab")
		)
		(pad "1" smd circle
			(at 0.40005 0 90)
			(size 0 0)
			(layers "B.Cu" "B.Mask" "B.Paste")
			(net "OCP_SFF_ISO_BIF0_EN")
		)
		(pad "2" smd circle
			(at -0.40005 0 90)
			(size 0 0)
			(layers "B.Cu" "B.Mask" "B.Paste")
			(net "GND")
		)
	)
	(footprint ""
		(layer "B.Cu")
		(at 238.14278 -245.730268)
		(property "Reference" "L17"
			(at 0 0 0)
			(layer "B.SilkS")
			(hide yes)
			(effects
				(font
					(size 1.27 1.27)
				)
				(justify mirror)
			)
		)
		(property "Value" ""
			(at 0 0 0)
			(layer "B.Fab")
			(effects
				(font
					(size 1.27 1.27)
				)
				(justify mirror)
			)
		)
		(duplicate_pad_numbers_are_jumpers no)
		(fp_line
			(start -1.63576 -0.8128)
			(end -1.63576 0.8128)
			(stroke
				(width 0.1524)
				(type default)
			)
			(layer "B.SilkS")
		)
		(fp_line
			(start -1.63576 0.8128)
			(end 1.63576 0.8128)
			(stroke
				(width 0.1524)
				(type default)
			)
			(layer "B.SilkS")
		)
		(fp_line
			(start 1.63576 -0.8128)
			(end -1.63576 -0.8128)
			(stroke
				(width 0.1524)
				(type default)
			)
			(layer "B.SilkS")
		)
		(fp_line
			(start 1.63576 -0.8128)
			(end 1.63576 0.8128)
			(stroke
				(width 0.1524)
				(type default)
			)
			(layer "B.SilkS")
		)
		(fp_line
			(start -1.560576 -0.738632)
			(end 1.56083 -0.738632)
			(stroke
				(width 0.1)
				(type default)
			)
			(layer "B.Fab")
		)
		(fp_line
			(start -1.560576 0.7366)
			(end -1.560576 -0.738632)
			(stroke
				(width 0.1)
				(type default)
			)
			(layer "B.Fab")
		)
		(fp_line
			(start -1.524 0.7366)
			(end -1.560576 0.7366)
			(stroke
				(width 0.1)
				(type default)
			)
			(layer "B.Fab")
		)
		(fp_line
			(start 1.524 0.7366)
			(end -1.524 0.7366)
			(stroke
				(width 0.1)
				(type default)
			)
			(layer "B.Fab")
		)
		(fp_line
			(start 1.56083 -0.738632)
			(end 1.56083 0.7366)
			(stroke
				(width 0.1)
				(type default)
			)
			(layer "B.Fab")
		)
		(fp_line
			(start 1.56083 0.7366)
			(end 1.524 0.7366)
			(stroke
				(width 0.1)
				(type default)
			)
			(layer "B.Fab")
		)
		(pad "1" smd rect
			(at 0.94996 0)
			(size 1.1176 1.3716)
			(layers "B.Cu" "B.Mask" "B.Paste")
			(net "P3V3_AUX")
		)
		(pad "2" smd rect
			(at -0.94996 0)
			(size 1.1176 1.3716)
			(layers "B.Cu" "B.Mask" "B.Paste")
			(net "VFG3P3_CLK_GEN")
		)
	)
	(footprint ""
		(layer "B.Cu")
		(at 305.420014 -321.549776 -90)
		(property "Reference" "C3"
			(at 0 0 90)
			(layer "B.SilkS")
			(hide yes)
			(effects
				(font
					(size 1.27 1.27)
				)
				(justify mirror)
			)
		)
		(property "Value" ""
			(at 0 0 90)
			(layer "B.Fab")
			(effects
				(font
					(size 1.27 1.27)
				)
				(justify mirror)
			)
		)
		(duplicate_pad_numbers_are_jumpers no)
		(fp_line
			(start -1.524 0.762)
			(end 1.524 0.762)
			(stroke
				(width 0.1524)
				(type default)
			)
			(layer "B.SilkS")
		)
		(fp_line
			(start 1.524 0.762)
			(end 1.524 -0.762)
			(stroke
				(width 0.1524)
				(type default)
			)
			(layer "B.SilkS")
		)
		(fp_line
			(start -1.524 -0.762)
			(end -1.524 0.762)
			(stroke
				(width 0.1524)
				(type default)
			)
			(layer "B.SilkS")
		)
		(fp_line
			(start 1.524 -0.762)
			(end -1.524 -0.762)
			(stroke
				(width 0.1524)
				(type default)
			)
			(layer "B.SilkS")
		)
		(fp_line
			(start -1.1049 0.724916)
			(end -1.1049 -0.724916)
			(stroke
				(width 0.1)
				(type default)
			)
			(layer "B.Fab")
		)
		(fp_line
			(start 1.1049 0.724916)
			(end -1.1049 0.724916)
			(stroke
				(width 0.1)
				(type default)
			)
			(layer "B.Fab")
		)
		(fp_line
			(start -1.1049 -0.724916)
			(end 1.1049 -0.724916)
			(stroke
				(width 0.1)
				(type default)
			)
			(layer "B.Fab")
		)
		(fp_line
			(start 1.1049 -0.724916)
			(end 1.1049 0.724916)
			(stroke
				(width 0.1)
				(type default)
			)
			(layer "B.Fab")
		)
		(pad "1" smd rect
			(at 0.889 0 270)
			(size 1.016 1.27)
			(layers "B.Cu" "B.Mask" "B.Paste")
			(net "P12V_S3_AUX_CPU0_NVDIMM")
		)
		(pad "2" smd rect
			(at -0.889 0 270)
			(size 1.016 1.27)
			(layers "B.Cu" "B.Mask" "B.Paste")
			(net "GND")
		)
	)
)
